# S9S_MB_2U (Grand Teton) — schematic netlist excerpt (pin names and nets, part order shuffled) for the footprints in the layout excerpt that follows; sources: Cadence DE-HDL packaged netlist, KiCad conversion of 03242023_DA0F0TMBIJ0_F0T_Motherboard_J_brd_V01_OCP.brd

X27  TP_TDR_4P_FTS  TP_TDR_4P_DIP EMPTY  pkg TH  page 309
  S1  = TDR_DIFF_85_IN5_DN
  P1  = T1_GND
  P2  = T1_GND
  S2  = TDR_DIFF_85_IN5_DP

PC611_P0_2  Q_CAP  22UF 16V 20% X6S  pkg C0805  page 271 : A = SW_P12V_PVCCFA_EHV_FIVRA_CPU0_L ; B = GND

(kicad_pcb
	(version 20260206)
	(generator "pcbnew")
	(generator_version "10.0")
	(general
		(thickness 1.6)
		(legacy_teardrops no)
	)
	(paper "A4")
	(title_block
		(title "03242023_DA0F0TMBIJ0_F0T_Motherboard_J_brd_V01_OCP.brd")
		(comment 1 "Grand Teton / footprints 5800-5801 of 6105")
	)
	(layers
		(0 "F.Cu" signal "TOP")
		(4 "In1.Cu" signal "GND")
		(6 "In2.Cu" signal "IN1")
		(8 "In3.Cu" signal "GND1")
		(10 "In4.Cu" signal "IN2")
		(12 "In5.Cu" signal "GND2")
		(14 "In6.Cu" signal "IN3")
		(16 "In7.Cu" signal "GND3")
		(18 "In8.Cu" signal "VCC")
		(20 "In9.Cu" signal "VCC1")
		(22 "In10.Cu" signal "GND4")
		(24 "In11.Cu" signal "IN4")
		(26 "In12.Cu" signal "GND5")
		(28 "In13.Cu" signal "IN5")
		(30 "In14.Cu" signal "GND6")
		(32 "In15.Cu" signal "IN6")
		(34 "In16.Cu" signal "GND7")
		(2 "B.Cu" signal "BOTTOM")
		(9 "F.Adhes" user "F.Adhesive")
		(11 "B.Adhes" user "B.Adhesive")
		(13 "F.Paste" user "Package Geometry/Pastemask Top")
		(15 "B.Paste" user "Package Geometry/Pastemask Bottom")
		(5 "F.SilkS" user "Ref Des/Silkscreen Top")
		(7 "B.SilkS" user "Ref Des/Silkscreen Bottom")
		(1 "F.Mask" user "Board Geometry/Soldermask Top")
		(3 "B.Mask" user "Board Geometry/Soldermask Bottom")
		(17 "Dwgs.User" user "User.Drawings")
		(19 "Cmts.User" user "User.Comments")
		(21 "Eco1.User" user "User.Eco1")
		(23 "Eco2.User" user "User.Eco2")
		(25 "Edge.Cuts" user "Board Geometry/Outline")
		(27 "Margin" user)
		(31 "F.CrtYd" user "Package Geometry/Place Bound Top")
		(29 "B.CrtYd" user "Package Geometry/Place Bound Bottom")
		(35 "F.Fab" user "Ref Des/Assembly Top")
		(33 "B.Fab" user "Ref Des/Assembly Bottom")
	)
	(footprint ""
		(layer "B.Cu")
		(at 301.731172 -362.795058 90)
		(property "Reference" "PC611_P0_2"
			(at 0 0 90)
			(layer "B.SilkS")
			(hide yes)
			(effects
				(font
					(size 1.27 1.27)
				)
				(justify mirror)
			)
		)
		(property "Value" ""
			(at 0 0 90)
			(layer "B.Fab")
			(effects
				(font
					(size 1.27 1.27)
				)
				(justify mirror)
			)
		)
		(duplicate_pad_numbers_are_jumpers no)
		(fp_line
			(start 1.524 -0.762)
			(end -1.524 -0.762)
			(stroke
				(width 0.1524)
				(type default)
			)
			(layer "B.SilkS")
		)
		(fp_line
			(start -1.524 -0.762)
			(end -1.524 0.762)
			(stroke
				(width 0.1524)
				(type default)
			)
			(layer "B.SilkS")
		)
		(fp_line
			(start 1.524 0.762)
			(end 1.524 -0.762)
			(stroke
				(width 0.1524)
				(type default)
			)
			(layer "B.SilkS")
		)
		(fp_line
			(start -1.524 0.762)
			(end 1.524 0.762)
			(stroke
				(width 0.1524)
				(type default)
			)
			(layer "B.SilkS")
		)
		(fp_line
			(start 1.1049 -0.724916)
			(end 1.1049 0.724916)
			(stroke
				(width 0.1)
				(type default)
			)
			(layer "B.Fab")
		)
		(fp_line
			(start -1.1049 -0.724916)
			(end 1.1049 -0.724916)
			(stroke
				(width 0.1)
				(type default)
			)
			(layer "B.Fab")
		)
		(fp_line
			(start 1.1049 0.724916)
			(end -1.1049 0.724916)
			(stroke
				(width 0.1)
				(type default)
			)
			(layer "B.Fab")
		)
		(fp_line
			(start -1.1049 0.724916)
			(end -1.1049 -0.724916)
			(stroke
				(width 0.1)
				(type default)
			)
			(layer "B.Fab")
		)
		(pad "1" smd rect
			(at 0.889 0 90)
			(size 1.016 1.27)
			(layers "B.Cu" "B.Mask" "B.Paste")
			(net "SW_P12V_PVCCFA_EHV_FIVRA_CPU0_L")
		)
		(pad "2" smd rect
			(at -0.889 0 90)
			(size 1.016 1.27)
			(layers "B.Cu" "B.Mask" "B.Paste")
			(net "GND")
		)
	)
	(footprint ""
		(layer "B.Cu")
		(at 511.924808 -303.58588 -90)
		(property "Reference" "X27"
			(at 3.47472 2.673858 270)
			(unlocked yes)
			(layer "B.SilkS")
			(effects
				(font
					(size 0.7874 0.5842)
					(thickness 0.1524)
				)
				(justify left mirror)
			)
		)
		(property "Value" ""
			(at 0 0 90)
			(layer "B.Fab")
			(effects
				(font
					(size 1.27 1.27)
				)
				(justify mirror)
			)
		)
		(property "Device Type" "TP_TDR_4P_FTS_TH-TP_TDR_4P_DIPA"
			(at -1.30175 1.27 180)
			(unlocked yes)
			(layer "B.Fab")
			(hide yes)
			(effects
				(font
					(size 0.635 0.4064)
					(thickness 0.1524)
				)
				(justify mirror)
			)
		)
		(property "User Part Number" "N_A"
			(at -1.30175 1.27 180)
			(unlocked yes)
			(layer "Cmts.User")
			(hide yes)
			(effects
				(font
					(size 0.635 0.4064)
					(thickness 0.1524)
				)
				(justify mirror)
			)
		)
		(duplicate_pad_numbers_are_jumpers no)
		(fp_line
			(start -2.54 3.81)
			(end -2.54 3.6703)
			(stroke
				(width 0.1524)
				(type default)
			)
			(layer "B.SilkS")
		)
		(fp_line
			(start 0 3.81)
			(end -2.54 3.81)
			(stroke
				(width 0.1524)
				(type default)
			)
			(layer "B.SilkS")
		)
		(fp_line
			(start 0 3.175)
			(end 0 3.81)
			(stroke
				(width 0.1524)
				(type default)
			)
			(layer "B.SilkS")
		)
		(fp_line
			(start -2.54 1.4097)
			(end -2.54 1.1303)
			(stroke
				(width 0.1524)
				(type default)
			)
			(layer "B.SilkS")
		)
		(fp_line
			(start 0 0.635)
			(end 0 1.905)
			(stroke
				(width 0.1524)
				(type default)
			)
			(layer "B.SilkS")
		)
		(fp_line
			(start -2.54 -1.1303)
			(end -2.54 -1.27)
			(stroke
				(width 0.1524)
				(type default)
			)
			(layer "B.SilkS")
		)
		(fp_line
			(start -2.54 -1.27)
			(end 0 -1.27)
			(stroke
				(width 0.1524)
				(type default)
			)
			(layer "B.SilkS")
		)
		(fp_line
			(start 0 -1.27)
			(end 0 -0.635)
			(stroke
				(width 0.1524)
				(type default)
			)
			(layer "B.SilkS")
		)
		(fp_poly
			(pts
				(xy 3.001518 -0.804164) (xy 3.001518 0.719836) (xy 1.477518 -0.042164)
			)
			(stroke
				(width 0)
				(type default)
			)
			(fill yes)
			(layer "B.SilkS")
		)
		(fp_line
			(start -2.54 3.81)
			(end -2.54 -1.27)
			(stroke
				(width 0.1)
				(type default)
			)
			(layer "B.Fab")
		)
		(fp_line
			(start 0 3.81)
			(end -2.54 3.81)
			(stroke
				(width 0.1)
				(type default)
			)
			(layer "B.Fab")
		)
		(fp_line
			(start -2.54 -1.27)
			(end 0 -1.27)
			(stroke
				(width 0.1)
				(type default)
			)
			(layer "B.Fab")
		)
		(fp_line
			(start 0 -1.27)
			(end 0 3.81)
			(stroke
				(width 0.1)
				(type default)
			)
			(layer "B.Fab")
		)
		(fp_poly
			(pts
				(xy 0.761746 0) (xy 2.285746 -0.762) (xy 2.285746 0.762)
			)
			(stroke
				(width 0)
				(type default)
			)
			(fill yes)
			(layer "B.Fab")
		)
		(pad "1" thru_hole circle
			(at 0 0 90)
			(size 1.0033 1.0033)
			(drill 0.249936)
			(layers "*.Cu" "*.Mask")
			(remove_unused_layers no)
			(net "TDR_DIFF_85_IN5_DN")
			(clearance 0.10795)
			(padstack
				(mode front_inner_back)
				(layer "Inner"
					(shape circle)
					(size 0.8001 0.8001)
					(clearance 0.1524)
				)
				(layer "B.Cu"
					(shape circle)
					(size 1.0033 1.0033)
					(thermal_gap 0.10795)
					(clearance 0.10795)
				)
			)
		)
		(pad "2" thru_hole circle
			(at -2.54 0 90)
			(size 1.9939 1.9939)
			(drill 0.249936)
			(layers "*.Cu" "*.Mask")
			(remove_unused_layers no)
			(net "T1_GND")
			(clearance 0.10795)
			(padstack
				(mode front_inner_back)
				(layer "Inner"
					(shape circle)
					(size 0.8001 0.8001)
					(clearance 0.1524)
				)
				(layer "B.Cu"
					(shape circle)
					(size 1.9939 1.9939)
					(thermal_gap 0.10795)
					(clearance 0.10795)
				)
			)
		)
		(pad "3" thru_hole circle
			(at -2.54 2.54 90)
			(size 1.9939 1.9939)
			(drill 0.249936)
			(layers "*.Cu" "*.Mask")
			(remove_unused_layers no)
			(net "T1_GND")
			(clearance 0.10795)
			(padstack
				(mode front_inner_back)
				(layer "Inner"
					(shape circle)
					(size 0.8001 0.8001)
					(clearance 0.1524)
				)
				(layer "B.Cu"
					(shape circle)
					(size 1.9939 1.9939)
					(thermal_gap 0.10795)
					(clearance 0.10795)
				)
			)
		)
		(pad "4" thru_hole circle
			(at 0 2.54 90)
			(size 1.0033 1.0033)
			(drill 0.249936)
			(layers "*.Cu" "*.Mask")
			(remove_unused_layers no)
			(net "TDR_DIFF_85_IN5_DP")
			(clearance 0.10795)
			(padstack
				(mode front_inner_back)
				(layer "Inner"
					(shape circle)
					(size 0.8001 0.8001)
					(clearance 0.1524)
				)
				(layer "B.Cu"
					(shape circle)
					(size 1.0033 1.0033)
					(thermal_gap 0.10795)
					(clearance 0.10795)
				)
			)
		)
	)
)
